(kicad_pcb
	(version 20260206)
	(generator "pcbnew")
	(generator_version "10.0")
	(general
		(thickness 1.6)
		(legacy_teardrops no)
	)
	(paper "A4")
	(title_block
		(title "9052_F0T_PDB_Converter_Brick_F_V03_1208_1600_OCP.brd")
		(comment 1 "Grand Teton / footprints 294-301 of 578")
	)
	(layers
		(0 "F.Cu" signal "TOP")
		(4 "In1.Cu" signal "GND")
		(6 "In2.Cu" signal "IN1")
		(8 "In3.Cu" signal "GND1")
		(10 "In4.Cu" signal "VCC")
		(12 "In5.Cu" signal "VCC1")
		(14 "In6.Cu" signal "GND2")
		(16 "In7.Cu" signal "IN2")
		(18 "In8.Cu" signal "GND3")
		(2 "B.Cu" signal "BOTTOM")
		(9 "F.Adhes" user "F.Adhesive")
		(11 "B.Adhes" user "B.Adhesive")
		(13 "F.Paste" user "Package Geometry/Pastemask Top")
		(15 "B.Paste" user "Package Geometry/Pastemask Bottom")
		(5 "F.SilkS" user "Ref Des/Silkscreen Top")
		(7 "B.SilkS" user "Ref Des/Silkscreen Bottom")
		(1 "F.Mask" user "Board Geometry/Soldermask Top")
		(3 "B.Mask" user "Board Geometry/Soldermask Bottom")
		(17 "Dwgs.User" user "User.Drawings")
		(19 "Cmts.User" user "User.Comments")
		(21 "Eco1.User" user "User.Eco1")
		(23 "Eco2.User" user "User.Eco2")
		(25 "Edge.Cuts" user "Board Geometry/Outline")
		(27 "Margin" user)
		(31 "F.CrtYd" user "Package Geometry/Place Bound Top")
		(29 "B.CrtYd" user "Package Geometry/Place Bound Bottom")
		(35 "F.Fab" user "Ref Des/Assembly Top")
		(33 "B.Fab" user "Ref Des/Assembly Bottom")
	)
	(footprint ""
		(layer "F.Cu")
		(at 278.883872 -46.634146 180)
		(property "Reference" "PC561"
			(at 0 0 180)
			(layer "F.SilkS")
			(hide yes)
			(effects
				(font
					(size 1.27 1.27)
				)
			)
		)
		(property "Value" ""
			(at 0 0 180)
			(layer "F.Fab")
			(effects
				(font
					(size 1.27 1.27)
				)
			)
		)
		(duplicate_pad_numbers_are_jumpers no)
		(fp_line
			(start 0.7874 0.4064)
			(end -0.7874 0.4064)
			(stroke
				(width 0.1524)
				(type default)
			)
			(layer "F.SilkS")
		)
		(fp_line
			(start 0.7874 -0.4064)
			(end 0.7874 0.4064)
			(stroke
				(width 0.1524)
				(type default)
			)
			(layer "F.SilkS")
		)
		(fp_line
			(start -0.7874 0.4064)
			(end -0.7874 -0.4064)
			(stroke
				(width 0.1524)
				(type default)
			)
			(layer "F.SilkS")
		)
		(fp_line
			(start -0.7874 -0.4064)
			(end 0.7874 -0.4064)
			(stroke
				(width 0.1524)
				(type default)
			)
			(layer "F.SilkS")
		)
		(fp_line
			(start 0.67945 0.3048)
			(end 0.120396 0.3048)
			(stroke
				(width 0.1)
				(type default)
			)
			(layer "F.Fab")
		)
		(fp_line
			(start 0.67945 -0.3048)
			(end 0.67945 0.3048)
			(stroke
				(width 0.1)
				(type default)
			)
			(layer "F.Fab")
		)
		(fp_line
			(start 0.12065 -0.2794)
			(end 0.12065 -0.3048)
			(stroke
				(width 0.1)
				(type default)
			)
			(layer "F.Fab")
		)
		(fp_line
			(start 0.12065 -0.3048)
			(end 0.67945 -0.3048)
			(stroke
				(width 0.1)
				(type default)
			)
			(layer "F.Fab")
		)
		(fp_line
			(start 0.120396 0.3048)
			(end 0.120396 0.2794)
			(stroke
				(width 0.1)
				(type default)
			)
			(layer "F.Fab")
		)
		(fp_line
			(start 0.120396 0.2794)
			(end -0.12065 0.2794)
			(stroke
				(width 0.1)
				(type default)
			)
			(layer "F.Fab")
		)
		(fp_line
			(start -0.12065 0.3048)
			(end -0.67945 0.3048)
			(stroke
				(width 0.1)
				(type default)
			)
			(layer "F.Fab")
		)
		(fp_line
			(start -0.12065 0.2794)
			(end -0.12065 0.3048)
			(stroke
				(width 0.1)
				(type default)
			)
			(layer "F.Fab")
		)
		(fp_line
			(start -0.12065 -0.2794)
			(end 0.12065 -0.2794)
			(stroke
				(width 0.1)
				(type default)
			)
			(layer "F.Fab")
		)
		(fp_line
			(start -0.12065 -0.305054)
			(end -0.12065 -0.2794)
			(stroke
				(width 0.1)
				(type default)
			)
			(layer "F.Fab")
		)
		(fp_line
			(start -0.67945 0.3048)
			(end -0.67945 -0.305054)
			(stroke
				(width 0.1)
				(type default)
			)
			(layer "F.Fab")
		)
		(fp_line
			(start -0.67945 -0.305054)
			(end -0.12065 -0.305054)
			(stroke
				(width 0.1)
				(type default)
			)
			(layer "F.Fab")
		)
		(pad "1" smd circle
			(at -0.40005 0 180)
			(size 0 0)
			(layers "F.Cu" "F.Mask" "F.Paste")
			(net "P52V_HS1_ISET")
		)
		(pad "2" smd circle
			(at 0.40005 0 180)
			(size 0 0)
			(layers "F.Cu" "F.Mask" "F.Paste")
			(net "GND_FIELD_SIGNAL")
		)
	)
	(footprint ""
		(layer "F.Cu")
		(at 287.767014 -32.577024 90)
		(property "Reference" "PR17"
			(at 0 0 90)
			(layer "F.SilkS")
			(hide yes)
			(effects
				(font
					(size 1.27 1.27)
				)
			)
		)
		(property "Value" ""
			(at 0 0 90)
			(layer "F.Fab")
			(effects
				(font
					(size 1.27 1.27)
				)
			)
		)
		(duplicate_pad_numbers_are_jumpers no)
		(fp_line
			(start 1.651 -0.8382)
			(end 1.651 0.8382)
			(stroke
				(width 0.1524)
				(type default)
			)
			(layer "F.SilkS")
		)
		(fp_line
			(start -1.651 -0.8382)
			(end 1.651 -0.8382)
			(stroke
				(width 0.1524)
				(type default)
			)
			(layer "F.SilkS")
		)
		(fp_line
			(start 1.651 0.8382)
			(end -1.651 0.8382)
			(stroke
				(width 0.1524)
				(type default)
			)
			(layer "F.SilkS")
		)
		(fp_line
			(start -1.651 0.8382)
			(end -1.651 -0.8382)
			(stroke
				(width 0.1524)
				(type default)
			)
			(layer "F.SilkS")
		)
		(fp_line
			(start 1.560576 -0.7366)
			(end 1.524 -0.7366)
			(stroke
				(width 0.1)
				(type default)
			)
			(layer "F.Fab")
		)
		(fp_line
			(start 1.524 -0.7366)
			(end -1.524 -0.7366)
			(stroke
				(width 0.1)
				(type default)
			)
			(layer "F.Fab")
		)
		(fp_line
			(start -1.524 -0.7366)
			(end -1.559814 -0.7366)
			(stroke
				(width 0.1)
				(type default)
			)
			(layer "F.Fab")
		)
		(fp_line
			(start -1.559814 -0.7366)
			(end -1.559814 0.7366)
			(stroke
				(width 0.1)
				(type default)
			)
			(layer "F.Fab")
		)
		(fp_line
			(start 1.560576 0.7366)
			(end 1.560576 -0.7366)
			(stroke
				(width 0.1)
				(type default)
			)
			(layer "F.Fab")
		)
		(fp_line
			(start 1.524 0.7366)
			(end 1.560576 0.7366)
			(stroke
				(width 0.1)
				(type default)
			)
			(layer "F.Fab")
		)
		(fp_line
			(start -1.524 0.7366)
			(end 1.524 0.7366)
			(stroke
				(width 0.1)
				(type default)
			)
			(layer "F.Fab")
		)
		(fp_line
			(start -1.559814 0.7366)
			(end -1.524 0.7366)
			(stroke
				(width 0.1)
				(type default)
			)
			(layer "F.Fab")
		)
		(pad "1" smd rect
			(at -0.94996 0 270)
			(size 1.1176 1.3716)
			(layers "F.Cu" "F.Mask" "F.Paste")
			(net "P52V_HS")
		)
		(pad "2" smd rect
			(at 0.94996 0 270)
			(size 1.1176 1.3716)
			(layers "F.Cu" "F.Mask" "F.Paste")
			(net "P52V_HS1_PWRGIN")
		)
	)
	(footprint ""
		(layer "F.Cu")
		(at 286.554672 -36.209224)
		(property "Reference" "PR6935"
			(at 0 0 0)
			(layer "F.SilkS")
			(hide yes)
			(effects
				(font
					(size 1.27 1.27)
				)
			)
		)
		(property "Value" ""
			(at 0 0 0)
			(layer "F.Fab")
			(effects
				(font
					(size 1.27 1.27)
				)
			)
		)
		(duplicate_pad_numbers_are_jumpers no)
		(fp_line
			(start -0.7874 -0.4064)
			(end 0.7874 -0.4064)
			(stroke
				(width 0.1524)
				(type default)
			)
			(layer "F.SilkS")
		)
		(fp_line
			(start -0.7874 0.4064)
			(end -0.7874 -0.4064)
			(stroke
				(width 0.1524)
				(type default)
			)
			(layer "F.SilkS")
		)
		(fp_line
			(start 0.7874 -0.4064)
			(end 0.7874 0.4064)
			(stroke
				(width 0.1524)
				(type default)
			)
			(layer "F.SilkS")
		)
		(fp_line
			(start 0.7874 0.4064)
			(end -0.7874 0.4064)
			(stroke
				(width 0.1524)
				(type default)
			)
			(layer "F.SilkS")
		)
		(fp_line
			(start -0.67945 -0.305054)
			(end -0.12065 -0.305054)
			(stroke
				(width 0.1)
				(type default)
			)
			(layer "F.Fab")
		)
		(fp_line
			(start -0.67945 0.3048)
			(end -0.67945 -0.305054)
			(stroke
				(width 0.1)
				(type default)
			)
			(layer "F.Fab")
		)
		(fp_line
			(start -0.12065 -0.305054)
			(end -0.12065 -0.2794)
			(stroke
				(width 0.1)
				(type default)
			)
			(layer "F.Fab")
		)
		(fp_line
			(start -0.12065 -0.2794)
			(end 0.12065 -0.2794)
			(stroke
				(width 0.1)
				(type default)
			)
			(layer "F.Fab")
		)
		(fp_line
			(start -0.12065 0.2794)
			(end -0.12065 0.3048)
			(stroke
				(width 0.1)
				(type default)
			)
			(layer "F.Fab")
		)
		(fp_line
			(start -0.12065 0.3048)
			(end -0.67945 0.3048)
			(stroke
				(width 0.1)
				(type default)
			)
			(layer "F.Fab")
		)
		(fp_line
			(start 0.120396 0.2794)
			(end -0.12065 0.2794)
			(stroke
				(width 0.1)
				(type default)
			)
			(layer "F.Fab")
		)
		(fp_line
			(start 0.120396 0.3048)
			(end 0.120396 0.2794)
			(stroke
				(width 0.1)
				(type default)
			)
			(layer "F.Fab")
		)
		(fp_line
			(start 0.12065 -0.3048)
			(end 0.67945 -0.3048)
			(stroke
				(width 0.1)
				(type default)
			)
			(layer "F.Fab")
		)
		(fp_line
			(start 0.12065 -0.2794)
			(end 0.12065 -0.3048)
			(stroke
				(width 0.1)
				(type default)
			)
			(layer "F.Fab")
		)
		(fp_line
			(start 0.67945 -0.3048)
			(end 0.67945 0.3048)
			(stroke
				(width 0.1)
				(type default)
			)
			(layer "F.Fab")
		)
		(fp_line
			(start 0.67945 0.3048)
			(end 0.120396 0.3048)
			(stroke
				(width 0.1)
				(type default)
			)
			(layer "F.Fab")
		)
		(pad "1" smd circle
			(at -0.40005 0)
			(size 0 0)
			(layers "F.Cu" "F.Mask" "F.Paste")
			(net "PWRGD_P52V_HS1_PG")
		)
		(pad "2" smd circle
			(at 0.40005 0)
			(size 0 0)
			(layers "F.Cu" "F.Mask" "F.Paste")
			(net "P52V_HS1_PWRGIN")
		)
	)
	(footprint ""
		(layer "F.Cu")
		(at 244.97284 -4.3053)
		(property "Reference" "H22"
			(at -1.143 -3.40233 0)
			(unlocked yes)
			(layer "F.SilkS")
			(effects
				(font
					(size 0.7874 0.5842)
					(thickness 0.1524)
				)
				(justify left)
			)
		)
		(property "Value" ""
			(at 0 0 0)
			(layer "F.Fab")
			(effects
				(font
					(size 1.27 1.27)
				)
			)
		)
		(duplicate_pad_numbers_are_jumpers no)
		(fp_circle
			(center 0 0)
			(end 2.4003 0)
			(stroke
				(width 0.1524)
				(type default)
			)
			(fill no)
			(layer "F.SilkS")
		)
		(fp_circle
			(center 0 0)
			(end 6.5913 0)
			(stroke
				(width 0.1524)
				(type default)
			)
			(fill no)
			(layer "B.SilkS")
		)
		(fp_circle
			(center 0 0)
			(end 6.5913 0)
			(stroke
				(width 0.1)
				(type default)
			)
			(fill no)
			(layer "B.Fab")
		)
		(fp_circle
			(center 0 0)
			(end 2.4003 0)
			(stroke
				(width 0.1)
				(type default)
			)
			(fill no)
			(layer "F.Fab")
		)
		(pad "" np_thru_hole circle
			(at 0 0)
			(size 3.175 3.175)
			(drill 3.175)
			(layers "*.Cu" "*.Mask")
			(clearance 0.381)
			(thermal_gap 0.381)
		)
		(zone
			(layers "F.Cu" "B.Cu" "In1.Cu" "In2.Cu" "In3.Cu" "In4.Cu" "In5.Cu" "In6.Cu"
				"In7.Cu" "In8.Cu"
			)
			(hatch none 0.5)
			(connect_pads
				(clearance 0)
			)
			(min_thickness 0.25)
			(keepout
				(tracks not_allowed)
				(vias allowed)
				(pads allowed)
				(copperpour not_allowed)
				(footprints allowed)
			)
			(placement
				(enabled no)
				(sheetname "")
			)
			(fill
				(thermal_gap 0.5)
				(thermal_bridge_width 0.5)
				(island_removal_mode 0)
			)
			(polygon
				(pts
					(arc
						(start 247.06834 -4.3053)
						(mid 242.87734 -4.3053)
						(end 247.06834 -4.3053)
					)
				)
			)
		)
	)
	(footprint ""
		(layer "F.Cu")
		(at 287.782 -49.276 90)
		(property "Reference" "PC10"
			(at 0 0 90)
			(layer "F.SilkS")
			(hide yes)
			(effects
				(font
					(size 1.27 1.27)
				)
			)
		)
		(property "Value" ""
			(at 0 0 90)
			(layer "F.Fab")
			(effects
				(font
					(size 1.27 1.27)
				)
			)
		)
		(duplicate_pad_numbers_are_jumpers no)
		(fp_line
			(start 0.7874 -0.4064)
			(end 0.7874 0.4064)
			(stroke
				(width 0.1524)
				(type default)
			)
			(layer "F.SilkS")
		)
		(fp_line
			(start -0.7874 -0.4064)
			(end 0.7874 -0.4064)
			(stroke
				(width 0.1524)
				(type default)
			)
			(layer "F.SilkS")
		)
		(fp_line
			(start 0.7874 0.4064)
			(end -0.7874 0.4064)
			(stroke
				(width 0.1524)
				(type default)
			)
			(layer "F.SilkS")
		)
		(fp_line
			(start -0.7874 0.4064)
			(end -0.7874 -0.4064)
			(stroke
				(width 0.1524)
				(type default)
			)
			(layer "F.SilkS")
		)
		(fp_line
			(start -0.12065 -0.305054)
			(end -0.12065 -0.2794)
			(stroke
				(width 0.1)
				(type default)
			)
			(layer "F.Fab")
		)
		(fp_line
			(start -0.67945 -0.305054)
			(end -0.12065 -0.305054)
			(stroke
				(width 0.1)
				(type default)
			)
			(layer "F.Fab")
		)
		(fp_line
			(start 0.67945 -0.3048)
			(end 0.67945 0.3048)
			(stroke
				(width 0.1)
				(type default)
			)
			(layer "F.Fab")
		)
		(fp_line
			(start 0.12065 -0.3048)
			(end 0.67945 -0.3048)
			(stroke
				(width 0.1)
				(type default)
			)
			(layer "F.Fab")
		)
		(fp_line
			(start 0.12065 -0.2794)
			(end 0.12065 -0.3048)
			(stroke
				(width 0.1)
				(type default)
			)
			(layer "F.Fab")
		)
		(fp_line
			(start -0.12065 -0.2794)
			(end 0.12065 -0.2794)
			(stroke
				(width 0.1)
				(type default)
			)
			(layer "F.Fab")
		)
		(fp_line
			(start 0.120396 0.2794)
			(end -0.12065 0.2794)
			(stroke
				(width 0.1)
				(type default)
			)
			(layer "F.Fab")
		)
		(fp_line
			(start -0.12065 0.2794)
			(end -0.12065 0.3048)
			(stroke
				(width 0.1)
				(type default)
			)
			(layer "F.Fab")
		)
		(fp_line
			(start 0.67945 0.3048)
			(end 0.120396 0.3048)
			(stroke
				(width 0.1)
				(type default)
			)
			(layer "F.Fab")
		)
		(fp_line
			(start 0.120396 0.3048)
			(end 0.120396 0.2794)
			(stroke
				(width 0.1)
				(type default)
			)
			(layer "F.Fab")
		)
		(fp_line
			(start -0.12065 0.3048)
			(end -0.67945 0.3048)
			(stroke
				(width 0.1)
				(type default)
			)
			(layer "F.Fab")
		)
		(fp_line
			(start -0.67945 0.3048)
			(end -0.67945 -0.305054)
			(stroke
				(width 0.1)
				(type default)
			)
			(layer "F.Fab")
		)
		(pad "1" smd circle
			(at -0.40005 0 90)
			(size 0 0)
			(layers "F.Cu" "F.Mask" "F.Paste")
			(net "P52V_HS1_VREG")
		)
		(pad "2" smd circle
			(at 0.40005 0 90)
			(size 0 0)
			(layers "F.Cu" "F.Mask" "F.Paste")
			(net "GND_FIELD_SIGNAL")
		)
	)
	(footprint ""
		(layer "F.Cu")
		(at 163.576 -9.398)
		(property "Reference" "PC99"
			(at 0 0 0)
			(layer "F.SilkS")
			(hide yes)
			(effects
				(font
					(size 1.27 1.27)
				)
			)
		)
		(property "Value" ""
			(at 0 0 0)
			(layer "F.Fab")
			(effects
				(font
					(size 1.27 1.27)
				)
			)
		)
		(duplicate_pad_numbers_are_jumpers no)
		(fp_line
			(start -0.7874 -0.4064)
			(end 0.7874 -0.4064)
			(stroke
				(width 0.1524)
				(type default)
			)
			(layer "F.SilkS")
		)
		(fp_line
			(start -0.7874 0.4064)
			(end -0.7874 -0.4064)
			(stroke
				(width 0.1524)
				(type default)
			)
			(layer "F.SilkS")
		)
		(fp_line
			(start 0.7874 -0.4064)
			(end 0.7874 0.4064)
			(stroke
				(width 0.1524)
				(type default)
			)
			(layer "F.SilkS")
		)
		(fp_line
			(start 0.7874 0.4064)
			(end -0.7874 0.4064)
			(stroke
				(width 0.1524)
				(type default)
			)
			(layer "F.SilkS")
		)
		(fp_line
			(start -0.6858 -0.3048)
			(end -0.1016 -0.3048)
			(stroke
				(width 0.1)
				(type default)
			)
			(layer "F.Fab")
		)
		(fp_line
			(start -0.6858 0.3048)
			(end -0.6858 -0.3048)
			(stroke
				(width 0.1)
				(type default)
			)
			(layer "F.Fab")
		)
		(fp_line
			(start -0.1016 -0.3048)
			(end -0.1016 -0.2794)
			(stroke
				(width 0.1)
				(type default)
			)
			(layer "F.Fab")
		)
		(fp_line
			(start -0.1016 -0.2794)
			(end 0.1016 -0.2794)
			(stroke
				(width 0.1)
				(type default)
			)
			(layer "F.Fab")
		)
		(fp_line
			(start -0.1016 0.2794)
			(end -0.1016 0.3048)
			(stroke
				(width 0.1)
				(type default)
			)
			(layer "F.Fab")
		)
		(fp_line
			(start -0.1016 0.3048)
			(end -0.6858 0.3048)
			(stroke
				(width 0.1)
				(type default)
			)
			(layer "F.Fab")
		)
		(fp_line
			(start 0.1016 -0.3048)
			(end 0.6858 -0.3048)
			(stroke
				(width 0.1)
				(type default)
			)
			(layer "F.Fab")
		)
		(fp_line
			(start 0.1016 -0.2794)
			(end 0.1016 -0.3048)
			(stroke
				(width 0.1)
				(type default)
			)
			(layer "F.Fab")
		)
		(fp_line
			(start 0.1016 0.2794)
			(end -0.1016 0.2794)
			(stroke
				(width 0.1)
				(type default)
			)
			(layer "F.Fab")
		)
		(fp_line
			(start 0.1016 0.3048)
			(end 0.1016 0.2794)
			(stroke
				(width 0.1)
				(type default)
			)
			(layer "F.Fab")
		)
		(fp_line
			(start 0.6858 -0.3048)
			(end 0.6858 0.3048)
			(stroke
				(width 0.1)
				(type default)
			)
			(layer "F.Fab")
		)
		(fp_line
			(start 0.6858 0.3048)
			(end 0.1016 0.3048)
			(stroke
				(width 0.1)
				(type default)
			)
			(layer "F.Fab")
		)
		(pad "1" smd rect
			(at -0.40005 0 180)
			(size 0.4572 0.508)
			(layers "F.Cu" "F.Mask" "F.Paste")
			(net "P12V_BRICK")
		)
		(pad "2" smd rect
			(at 0.40005 0 180)
			(size 0.4572 0.508)
			(layers "F.Cu" "F.Mask" "F.Paste")
			(net "GND")
		)
	)
	(footprint ""
		(layer "F.Cu")
		(at 62.23 -8.509)
		(property "Reference" "DM1"
			(at 0 0 0)
			(layer "F.SilkS")
			(hide yes)
			(effects
				(font
					(size 1.27 1.27)
				)
			)
		)
		(property "Value" ""
			(at 0 0 0)
			(layer "F.Fab")
			(effects
				(font
					(size 1.27 1.27)
				)
			)
		)
		(duplicate_pad_numbers_are_jumpers no)
		(fp_line
			(start 0 -4.99999)
			(end 0 -3.47599)
			(stroke
				(width 0.1524)
				(type default)
			)
			(layer "F.SilkS")
		)
		(fp_line
			(start 1.524 -4.99999)
			(end 0 -4.99999)
			(stroke
				(width 0.1524)
				(type default)
			)
			(layer "F.SilkS")
		)
		(fp_text user "P/N"
			(at 0.361188 -3.449828 0)
			(unlocked yes)
			(layer "F.SilkS")
			(effects
				(font
					(size 1.905 1.4224)
					(thickness 0.1524)
				)
				(justify left)
			)
		)
	)
	(footprint ""
		(layer "F.Cu")
		(at 300.5074 -49.403 90)
		(property "Reference" "FS1"
			(at -0.889 -2.51333 90)
			(unlocked yes)
			(layer "F.SilkS")
			(effects
				(font
					(size 0.7874 0.5842)
					(thickness 0.1524)
				)
				(justify left)
			)
		)
		(property "Value" ""
			(at 0 0 90)
			(layer "F.Fab")
			(effects
				(font
					(size 1.27 1.27)
				)
			)
		)
		(duplicate_pad_numbers_are_jumpers no)
		(fp_line
			(start 6.427724 -1.8415)
			(end -6.427724 -1.8415)
			(stroke
				(width 0.1524)
				(type default)
			)
			(layer "F.SilkS")
		)
		(fp_line
			(start -6.427724 -1.8415)
			(end -6.427724 1.8415)
			(stroke
				(width 0.1524)
				(type default)
			)
			(layer "F.SilkS")
		)
		(fp_line
			(start 6.427724 1.8415)
			(end 6.427724 -1.8415)
			(stroke
				(width 0.1524)
				(type default)
			)
			(layer "F.SilkS")
		)
		(fp_line
			(start -6.427724 1.8415)
			(end 6.427724 1.8415)
			(stroke
				(width 0.1524)
				(type default)
			)
			(layer "F.SilkS")
		)
		(fp_line
			(start 5.050028 -1.560068)
			(end -5.050028 -1.560068)
			(stroke
				(width 0.1)
				(type default)
			)
			(layer "F.Fab")
		)
		(fp_line
			(start -5.050028 -1.560068)
			(end -5.050028 1.560068)
			(stroke
				(width 0.1)
				(type default)
			)
			(layer "F.Fab")
		)
		(fp_line
			(start 5.050028 1.560068)
			(end 5.050028 -1.560068)
			(stroke
				(width 0.1)
				(type default)
			)
			(layer "F.Fab")
		)
		(fp_line
			(start -5.050028 1.560068)
			(end 5.050028 1.560068)
			(stroke
				(width 0.1)
				(type default)
			)
			(layer "F.Fab")
		)
		(pad "1" smd rect
			(at -4.675124 0 90)
			(size 3.2512 3.429)
			(layers "F.Cu" "F.Mask" "F.Paste")
			(net "P52V_1_FUSE_1")
		)
		(pad "2" smd rect
			(at 4.675124 0 90)
			(size 3.2512 3.429)
			(layers "F.Cu" "F.Mask" "F.Paste")
			(net "P52V_1")
		)
	)
)
